FILE_TYPE = CONNECTIVITY;
{Allegro Design Entry HDL 17.2-2016 S066 (3851973) 4/6/2020}
"PAGE_NUMBER" = 15;
0"NC";
1"SG\g";
2"SG\g";
3"SG\g";
4"SG\g";
5"XP12R0V_IN\g";
6"SG\g";
7"XP12R0V_PCIE\g";
8"XP12R0V_EXT\g";
9"XP12R0V\g";
10"SG\g";
11"SG\g";
12"SG\g";
13"SG\g";
14"SG\g";
15"SG\g";
16"SG\g";
17"XP12R0V_A_EN";
18"UN$15$MP5022CGQVZQFN22$I212$LOADEN";
19"UN$15$MP5022CGQVZQFN22$I212$ENTM";
20"XP12R0V_A_FLTB";
21"XP12R0V_A_IMON";
22"XP12R0V_A_OV";
23"XP12R0V_A_PG";
24"XP12R0V_A_ISET";
25"XP12R0V_A_TIMER";
26"XP12R0V_A_SS";
27"XP12R0V_A_AVIN";
%"GND_SG"
"1","(-9050,7050)","0","cls","I148";
;
HDL_POWER"SG"
CDS_LIB"cls"
CDS_LMAN_SYM_OUTLINE"0,0,100,-50"
BODY_TYPE"PLUMBING";
"SGND"4;
%"CAPACITOR"
"2","(-9000,7400)","0","passive","I156";
;
$LOCATION"C3"
CDS_LOCATION"C3"
$SEC"1"
CDS_SEC"1"
VOLTAGE"25V"
PACKAGE"0402"
VALUE"0.1UF"
CDS_LIB"passive"
CDS_LMAN_SYM_OUTLINE"-50,0,50,-50"
TOLERANCE"10%"
CLS_PN"G105-0B104-EK";
"2"
$PN"2"4;
"1"
$PN"1"17;
%"GND_SG"
"1","(-9000,8350)","0","cls","I157";
;
HDL_POWER"SG"
CDS_LMAN_SYM_OUTLINE"0,0,100,-50"
CDS_LIB"cls"
BODY_TYPE"PLUMBING";
"SGND"16;
%"GND_SG"
"1","(-11200,8400)","0","cls","I158";
;
HDL_POWER"SG"
CDS_LIB"cls"
CDS_LMAN_SYM_OUTLINE"0,0,100,-50"
BODY_TYPE"PLUMBING";
"SGND"3;
%"DIODE_2E"
"1","(-11150,8950)","1","discrete","I159";
;
$LOCATION"CR10"
CDS_LOCATION"CR10"
$SEC"1"
CDS_SEC"1"
CLS_PN"G122-10190-01"
PART_NUMBER"SMDJ12A"
CDS_LIB"discrete"
CDS_LMAN_SYM_OUTLINE"-50,100,50,-100";
"C"
$PN"C"5;
"A"
$PN"A"3;
%"CAPACITOR"
"2","(-8950,9000)","0","passive","I160";
;
$LOCATION"C2"
CDS_LOCATION"C2"
$SEC"1"
CDS_SEC"1"
PACKAGE"0402"
VOLTAGE"25V"
VALUE"0.1UF"
TOLERANCE"10%"
CDS_LIB"passive"
CDS_LMAN_SYM_OUTLINE"-50,0,50,-50"
CLS_PN"G105-0B104-EK";
"2"
$PN"2"16;
"1"
$PN"1"5;
%"GND_SG"
"1","(-8500,7050)","0","cls","I166";
;
HDL_POWER"SG"
CDS_LIB"cls"
CDS_LMAN_SYM_OUTLINE"0,0,100,-50"
BODY_TYPE"PLUMBING";
"SGND"2;
%"GND_SG"
"1","(-7900,7050)","0","cls","I167";
;
HDL_POWER"SG"
CDS_LMAN_SYM_OUTLINE"0,0,100,-50"
CDS_LIB"cls"
BODY_TYPE"PLUMBING";
"SGND"15;
%"GND_SG"
"1","(-5250,6500)","0","cls","I168";
;
HDL_POWER"SG"
CDS_LIB"cls"
CDS_LMAN_SYM_OUTLINE"0,0,100,-50"
BODY_TYPE"PLUMBING";
"SGND"14;
%"RESISTOR"
"2","(-8450,7400)","0","passive","I169";
;
$LOCATION"R5"
CDS_LOCATION"R5"
$SEC"1"
CDS_SEC"1"
NO_ASSY"TRUE"
VALUE"10KOHM"
PACKAGE"0402"
CDS_LMAN_SYM_OUTLINE"-50,50,50,-100"
CDS_LIB"passive"
CLS_PN"G155-11002-01"
TOLERANCE"1%";
"1"
$PN"1"17;
"2"
$PN"2"2;
%"RESISTOR"
"2","(-8450,8850)","0","passive","I170";
;
$LOCATION"R4"
CDS_LOCATION"R4"
$SEC"1"
CDS_SEC"1"
PACKAGE"0402"
VALUE"10KOHM"
NO_ASSY"TRUE"
CDS_LIB"passive"
CDS_LMAN_SYM_OUTLINE"-50,50,50,-100"
CLS_PN"G155-11002-01"
TOLERANCE"1%";
"1"
$PN"1"5;
"2"
$PN"2"17;
%"RESISTOR"
"1","(-7550,7500)","0","passive","I171";
;
$LOCATION"R46"
CDS_LOCATION"R46"
$SEC"1"
CDS_SEC"1"
VALUE"26.7K"
PACKAGE"0402"
CLS_PN"G155-02672-01"
TOLERANCE"1%"
CDS_LIB"passive"
CDS_LMAN_SYM_OUTLINE"-50,50,100,-50";
"1"
$PN"1"15;
"2"
$PN"2"24;
%"CAPACITOR"
"1","(-7550,7700)","0","passive","I172";
;
$LOCATION"C4"
CDS_LOCATION"C4"
$SEC"1"
CDS_SEC"1"
PACKAGE"0201"
VALUE"0.22UF"
VOLTAGE"6.3V"
TOLERANCE"10%"
CDS_LMAN_SYM_OUTLINE"0,50,50,-50"
CDS_LIB"passive"
CLS_PN"G104-0F224-BK";
"2"
$PN"2"25;
"1"
$PN"1"15;
%"RESISTOR"
"1","(-7500,7900)","0","passive","I173";
;
$LOCATION"R8"
CDS_LOCATION"R8"
$SEC"1"
CDS_SEC"1"
VALUE"0OHM"
PACKAGE"0402"
CDS_LIB"passive"
CDS_LMAN_SYM_OUTLINE"-50,50,100,-50"
CLS_PN"G155-100R0-J0"
TOLERANCE"-";
"1"
$PN"1"15;
"2"
$PN"2"19;
%"RESISTOR"
"1","(-7500,8100)","0","passive","I174";
;
$LOCATION"R7"
CDS_LOCATION"R7"
$SEC"1"
CDS_SEC"1"
PACKAGE"0402"
VALUE"0OHM"
CDS_LMAN_SYM_OUTLINE"-50,50,100,-50"
CDS_LIB"passive"
CLS_PN"G155-100R0-J0"
TOLERANCE"-";
"1"
$PN"1"15;
"2"
$PN"2"18;
%"RESISTOR"
"2","(-4650,6950)","0","passive","I183";
;
$LOCATION"R10"
CDS_LOCATION"R10"
$SEC"1"
CDS_SEC"1"
PACKAGE"0402"
VALUE"10KOHM"
TOLERANCE"1%"
CLS_PN"G155-11002-01"
CDS_LIB"passive"
CDS_LMAN_SYM_OUTLINE"-50,50,50,-100";
"1"
$PN"1"21;
"2"
$PN"2"13;
%"GND_SG"
"1","(-4300,6500)","0","cls","I184";
;
HDL_POWER"SG"
BODY_TYPE"PLUMBING"
CDS_LIB"cls"
CDS_LMAN_SYM_OUTLINE"0,0,100,-50";
"SGND"13;
%"CAPACITOR"
"2","(-4250,6950)","0","passive","I185";
;
$LOCATION"C7"
CDS_LOCATION"C7"
$SEC"1"
CDS_SEC"1"
VALUE"0.1UF"
VOLTAGE"25V"
PACKAGE"0402"
CDS_LMAN_SYM_OUTLINE"-50,0,50,-50"
CDS_LIB"passive"
TOLERANCE"10%"
CLS_PN"G105-0B104-EK";
"2"
$PN"2"13;
"1"
$PN"1"21;
%"RESISTOR"
"2","(-3600,7250)","0","passive","I186";
;
$LOCATION"R14"
CDS_LOCATION"R14"
$SEC"1"
CDS_SEC"1"
VALUE"3.92KOHM"
PACKAGE"0402"
CLS_PN"G155-03921-01"
CDS_LIB"passive"
CDS_LMAN_SYM_OUTLINE"-50,50,50,-100"
TOLERANCE"1%";
"1"
$PN"1"23;
"2"
$PN"2"12;
%"GND_SG"
"1","(-3100,6750)","0","cls","I187";
;
HDL_POWER"SG"
CDS_LMAN_SYM_OUTLINE"0,0,100,-50"
CDS_LIB"cls"
BODY_TYPE"PLUMBING";
"SGND"12;
%"RESISTOR"
"2","(-3050,7250)","0","passive","I188";
;
$LOCATION"R16"
CDS_LOCATION"R16"
$SEC"1"
CDS_SEC"1"
PACKAGE"0402"
VALUE"3.92KOHM"
CLS_PN"G155-03921-01"
CDS_LIB"passive"
CDS_LMAN_SYM_OUTLINE"-50,50,50,-100"
TOLERANCE"1%";
"1"
$PN"1"20;
"2"
$PN"2"12;
%"GND_SG"
"1","(-5050,7950)","0","cls","I195";
;
HDL_POWER"SG"
CDS_LMAN_SYM_OUTLINE"0,0,100,-50"
CDS_LIB"cls"
BODY_TYPE"PLUMBING";
"SGND"1;
%"CAPACITOR"
"2","(-5000,8250)","0","passive","I196";
;
$LOCATION"C6"
CDS_LOCATION"C6"
$SEC"1"
CDS_SEC"1"
PACKAGE"0402"
VOLTAGE"25V"
VALUE"10UF"
CDS_LIB"passive"
CDS_LMAN_SYM_OUTLINE"-50,0,50,-50"
TOLERANCE"20%"
CLS_PN"G107-0F106-EM";
"2"
$PN"2"1;
"1"
$PN"1"27;
%"RESISTOR"
"2","(-4450,8250)","0","passive","I197";
;
$LOCATION"R12"
CDS_LOCATION"R12"
$SEC"1"
CDS_SEC"1"
PACKAGE"0402"
VALUE"10KOHM"
CDS_LMAN_SYM_OUTLINE"-50,50,50,-100"
CDS_LIB"passive"
CLS_PN"G155-11002-01"
TOLERANCE"1%";
"1"
$PN"1"22;
"2"
$PN"2"11;
%"RESISTOR"
"2","(-5000,8800)","0","passive","I198";
;
$LOCATION"R9"
CDS_LOCATION"R9"
$SEC"1"
CDS_SEC"1"
PACKAGE"0603"
VALUE"49.9OHM"
CDS_LMAN_SYM_OUTLINE"-50,50,50,-100"
CDS_LIB"passive"
CLS_PN"G156-049R9-01"
TOLERANCE"1%";
"1"
$PN"1"5;
"2"
$PN"2"27;
%"RESISTOR"
"2","(-4450,8750)","0","passive","I199";
;
$LOCATION"R11"
CDS_LOCATION"R11"
$SEC"1"
CDS_SEC"1"
VALUE"120KOHM"
PACKAGE"0402"
CDS_LMAN_SYM_OUTLINE"-50,50,50,-100"
CDS_LIB"passive"
CLS_PN"G155-01203-01"
TOLERANCE"1%";
"1"
$PN"1"5;
"2"
$PN"2"22;
%"GND_SG"
"1","(-4050,7900)","0","cls","I200";
;
HDL_POWER"SG"
CDS_LIB"cls"
CDS_LMAN_SYM_OUTLINE"0,0,100,-50"
BODY_TYPE"PLUMBING";
"SGND"11;
%"CAPACITOR"
"2","(-4000,8250)","0","passive","I201";
;
$LOCATION"C8"
CDS_LOCATION"C8"
$SEC"1"
CDS_SEC"1"
PACKAGE"0402"
VALUE"0.01UF"
VOLTAGE"25V"
CDS_LMAN_SYM_OUTLINE"-50,0,50,-50"
CDS_LIB"passive"
CLS_PN"G104-0B103-EK"
TOLERANCE"10%";
"2"
$PN"2"11;
"1"
$PN"1"22;
%"RESISTOR"
"2","(-3600,8050)","0","passive","I202";
;
$LOCATION"R13"
CDS_LOCATION"R13"
$SEC"1"
CDS_SEC"1"
VALUE"10KOHM"
PACKAGE"0402"
CDS_LIB"passive"
CDS_LMAN_SYM_OUTLINE"-50,50,50,-100"
CLS_PN"G155-11002-01"
TOLERANCE"1%";
"1"
$PN"1"9;
"2"
$PN"2"23;
%"RESISTOR"
"2","(-3050,8050)","0","passive","I203";
;
$LOCATION"R15"
CDS_LOCATION"R15"
$SEC"1"
CDS_SEC"1"
VALUE"10KOHM"
PACKAGE"0402"
CDS_LMAN_SYM_OUTLINE"-50,50,50,-100"
CDS_LIB"passive"
CLS_PN"G155-11002-01"
TOLERANCE"1%";
"1"
$PN"1"9;
"2"
$PN"2"20;
%"DIODE_2"
"1","(-2400,8500)","1","discrete","I204";
;
$LOCATION"CR3"
CDS_LOCATION"CR3"
$SEC"1"
CDS_SEC"1"
CLS_PN"G122-00005-01"
PART_NUMBER"MBRS240LT3G"
CDS_LMAN_SYM_OUTLINE"-50,50,50,-50"
CDS_LIB"discrete";
"C"
$PN"C"9;
"A"
$PN"A"10;
%"GND_SG"
"1","(-1350,8050)","0","cls","I205";
;
HDL_POWER"SG"
CDS_LMAN_SYM_OUTLINE"0,0,100,-50"
CDS_LIB"cls"
BODY_TYPE"PLUMBING";
"SGND"10;
%"CAPACITOR"
"2","(-1800,8650)","0","passive","I206";
;
$LOCATION"C9"
CDS_LOCATION"C9"
$SEC"1"
CDS_SEC"1"
VALUE"10UF"
VOLTAGE"25V"
PACKAGE"0805"
CLS_PN"G107-0F106-EM"
TOLERANCE"20%"
CDS_LMAN_SYM_OUTLINE"-50,0,50,-50"
CDS_LIB"passive";
"2"
$PN"2"10;
"1"
$PN"1"9;
%"CAPACITOR"
"2","(-1300,8650)","0","passive","I207";
;
$LOCATION"C10"
CDS_LOCATION"C10"
$SEC"1"
CDS_SEC"1"
VALUE"10UF"
VOLTAGE"25V"
PACKAGE"0805"
CDS_LIB"passive"
CDS_LMAN_SYM_OUTLINE"-50,0,50,-50"
TOLERANCE"20%"
CLS_PN"G107-0F106-EM";
"2"
$PN"2"10;
"1"
$PN"1"9;
%"VCC"
"1","(-900,9400)","0","cls","I209";
;
VOLTAGE"12V"
HDL_POWER"XP12R0V"
BODY_TYPE"PLUMBING"
CDS_LMAN_SYM_OUTLINE"-250,250,250,-250"
CDS_LIB"cls";
"$PIN0"9;
%"CAPACITOR"
"2","(-5200,6900)","0","passive","I211";
;
$LOCATION"C5"
CDS_LOCATION"C5"
$SEC"1"
CDS_SEC"1"
VOLTAGE"25V"
PACKAGE"0402"
VALUE"0.1UF"
CLS_PN"G105-0B104-EK"
TOLERANCE"10%"
CDS_LIB"passive"
CDS_LMAN_SYM_OUTLINE"-50,0,50,-50";
"2"
$PN"2"14;
"1"
$PN"1"26;
%"MP5022CGQV_Z_QFN22"
"1","(-6650,9100)","0","stdlogic","I212";
;
$LOCATION"U1"
CDS_LOCATION"U1"
$SEC"1"
CDS_SEC"1"
CLS_PN"G220-10510-01"
PART_NUMBER"MP5022CGQV-Z"
CDS_LMAN_SYM_OUTLINE"0,0,1000,-2300"
CDS_LIB"stdlogic";
"VOUT_8"
$PN"20"9;
"VOUT_7"
$PN"19"9;
"VOUT_6"
$PN"18"9;
"VOUT_5"
$PN"17"9;
"VOUT_4"
$PN"16"9;
"VOUT_3"
$PN"15"9;
"VOUT_2"
$PN"14"9;
"VOUT_1"
$PN"13"9;
"AVIN"
$PN"12"27;
"OV"
$PN"11"22;
"LOADEN"
$PN"2"18;
"GND"
$PN"7"14;
"VIN_6"
$PN"26"5;
"VIN_5"
$PN"25"5;
"VIN_4"
$PN"24"5;
"VIN_3"
$PN"23"5;
"VIN_2"
$PN"22"5;
"VIN_1"
$PN"21"5;
"PG"
$PN"10"23;
"FLTB"
$PN"9"20;
"IMON"
$PN"8"21;
"SS"
$PN"6"26;
"ISET"
$PN"5"24;
"TIMER"
$PN"4"25;
"ENTM"
$PN"3"19;
"EN"
$PN"1"17;
%"VCC"
"1","(-13300,9800)","0","cls","I213";
;
HDL_POWER"XP12R0V_EXT"
VOLTAGE"12"
BODY_TYPE"PLUMBING"
CDS_LMAN_SYM_OUTLINE"-250,250,250,-250"
CDS_LIB"cls";
"$PIN0"8;
%"VCC"
"1","(-12650,9800)","0","cls","I215";
;
VOLTAGE"12"
HDL_POWER"XP12R0V_PCIE"
BODY_TYPE"PLUMBING"
CDS_LMAN_SYM_OUTLINE"-250,250,250,-250"
CDS_LIB"cls";
"$PIN0"7;
%"FUSE"
"1","(-3500,9400)","0","passive","I223";
;
$LOCATION"FU1"
CDS_LOCATION"FU1"
$SEC"1"
CDS_SEC"1"
PACKAGE"0603"
VALUE"2.5A"
NO_ASSY"TRUE"
CDS_LIB"passive"
CDS_LMAN_SYM_OUTLINE"-50,50,100,-50"
CLS_PN"G280-10012-01";
"2"
$PN"2"9;
"1 \B"
$PN"1"5;
%"GND_SG"
"1","(-12300,7950)","0","cls","I226";
;
HDL_POWER"SG"
CDS_LIB"cls"
CDS_LMAN_SYM_OUTLINE"0,0,100,-50"
BODY_TYPE"PLUMBING";
"SGND"6;
%"CAPACITOR"
"2","(-10650,9000)","0","passive","I229";
;
$LOCATION"C297"
CDS_LOCATION"C297"
$SEC"1"
CDS_SEC"1"
PACKAGE"0805"
VALUE"10UF"
VOLTAGE"25V"
NO_ASSY"TRUE"
TOLERANCE"20%"
CLS_PN"G107-0F106-EM"
CDS_LMAN_SYM_OUTLINE"-50,0,50,-50"
CDS_LIB"passive";
"2"
$PN"2"16;
"1"
$PN"1"5;
%"CAPACITOR"
"2","(-10250,9000)","0","passive","I230";
;
$LOCATION"C299"
CDS_LOCATION"C299"
$SEC"1"
CDS_SEC"1"
VOLTAGE"25V"
VALUE"10UF"
NO_ASSY"TRUE"
PACKAGE"0805"
TOLERANCE"20%"
CLS_PN"G107-0F106-EM"
CDS_LMAN_SYM_OUTLINE"-50,0,50,-50"
CDS_LIB"passive";
"2"
$PN"2"16;
"1"
$PN"1"5;
%"CAPACITOR"
"2","(-9450,9000)","0","passive","I231";
;
$LOCATION"C303"
CDS_LOCATION"C303"
$SEC"1"
CDS_SEC"1"
VOLTAGE"25V"
VALUE"10UF"
NO_ASSY"TRUE"
PACKAGE"0805"
TOLERANCE"20%"
CLS_PN"G107-0F106-EM"
CDS_LMAN_SYM_OUTLINE"-50,0,50,-50"
CDS_LIB"passive";
"2"
$PN"2"16;
"1"
$PN"1"5;
%"CAPACITOR"
"2","(-9850,9000)","0","passive","I232";
;
$LOCATION"C301"
CDS_LOCATION"C301"
$SEC"1"
CDS_SEC"1"
VOLTAGE"25V"
VALUE"10UF"
NO_ASSY"TRUE"
PACKAGE"0805"
CDS_LIB"passive"
CDS_LMAN_SYM_OUTLINE"-50,0,50,-50"
CLS_PN"G107-0F106-EM"
TOLERANCE"20%";
"2"
$PN"2"16;
"1"
$PN"1"5;
%"CONN_HDR_2X3_M_RA_TH"
"1","(-12850,8450)","0","connector","I238";
;
LOCATION"P3"
$SEC"1"
CDS_SEC"1"
CLS_PN"G200-12517-01"
PART_NUMBER"457320001"
CDS_LIB"connector"
CDS_LMAN_SYM_OUTLINE"0,0,300,-400";
"6"
$PN"6"6;
"5"
$PN"5"6;
"4"
$PN"4"6;
"3"
$PN"3"8;
"2"
$PN"2"8;
"1"
$PN"1"8;
%"DIODE_3F"
"1","(-11950,9500)","0","discrete","I239";
;
LOCATION"CR12"
$SEC"1"
CDS_SEC"1"
CLS_PN"G122-10080-01"
PART_NUMBER"V20PW60C-M3/I"
CDS_LMAN_SYM_OUTLINE"0,0,250,-200"
CDS_LIB"discrete";
"C"
$PN"3"5;
"A_1"
$PN"1"7;
"A_2"
$PN"2"8;
%"FERRITEBEAD"
"1","(-11900,9700)","0","passive","I240";
;
LOCATION"L20"
$SEC"1"
CDS_SEC"1"
VALUE"26OHM"
NO_ASSY"TRUE"
PACKAGE"0603"
CDS_LIB"passive"
CDS_LMAN_SYM_OUTLINE"0,0,200,-100"
TOLERANCE"25%"
CLS_PN"G191-10101-01";
"2"
$PN"2"5;
"1"
$PN"1"7;
%"VCC"
"1","(-10800,9750)","0","cls","I245";
;
VOLTAGE"12"
HDL_POWER"XP12R0V_IN"
BODY_TYPE"PLUMBING"
CDS_LMAN_SYM_OUTLINE"-250,250,250,-250"
CDS_LIB"cls";
"$PIN0"5;
END.
